(kicad_pcb
	(version 20260206)
	(generator "pcbnew")
	(generator_version "10.0")
	(general
		(thickness 1.6)
		(legacy_teardrops no)
	)
	(paper "A4")
	(title_block
		(title "01162023_DA0F0TEBIF0_F0T_Expander_BD_F_brd_V02_OCP.brd")
		(comment 1 "Grand Teton / footprints 809-815 of 9728")
	)
	(layers
		(0 "F.Cu" signal "TOP")
		(4 "In1.Cu" signal "GND")
		(6 "In2.Cu" signal "VCC")
		(8 "In3.Cu" signal "VCC1")
		(10 "In4.Cu" signal "GND1")
		(12 "In5.Cu" signal "IN1")
		(14 "In6.Cu" signal "GND2")
		(16 "In7.Cu" signal "IN2")
		(18 "In8.Cu" signal "GND3")
		(20 "In9.Cu" signal "IN3")
		(22 "In10.Cu" signal "GND4")
		(24 "In11.Cu" signal "IN4")
		(26 "In12.Cu" signal "GND5")
		(28 "In13.Cu" signal "IN5")
		(30 "In14.Cu" signal "GND6")
		(32 "In15.Cu" signal "IN6")
		(34 "In16.Cu" signal "GND7")
		(2 "B.Cu" signal "BOTTOM")
		(9 "F.Adhes" user "F.Adhesive")
		(11 "B.Adhes" user "B.Adhesive")
		(13 "F.Paste" user "Package Geometry/Pastemask Top")
		(15 "B.Paste" user "Package Geometry/Pastemask Bottom")
		(5 "F.SilkS" user "Ref Des/Silkscreen Top")
		(7 "B.SilkS" user "Ref Des/Silkscreen Bottom")
		(1 "F.Mask" user "Board Geometry/Soldermask Top")
		(3 "B.Mask" user "Board Geometry/Soldermask Bottom")
		(17 "Dwgs.User" user "User.Drawings")
		(19 "Cmts.User" user "User.Comments")
		(21 "Eco1.User" user "User.Eco1")
		(23 "Eco2.User" user "User.Eco2")
		(25 "Edge.Cuts" user "Board Geometry/Outline")
		(27 "Margin" user)
		(31 "F.CrtYd" user "Package Geometry/Place Bound Top")
		(29 "B.CrtYd" user "Package Geometry/Place Bound Bottom")
		(35 "F.Fab" user "Ref Des/Assembly Top")
		(33 "B.Fab" user "Ref Des/Assembly Bottom")
	)
	(footprint ""
		(layer "F.Cu")
		(at 340.561422 -187.36945 180)
		(property "Reference" "R4237"
			(at 0 0 180)
			(layer "F.SilkS")
			(hide yes)
			(effects
				(font
					(size 1.27 1.27)
				)
			)
		)
		(property "Value" ""
			(at 0 0 180)
			(layer "F.Fab")
			(effects
				(font
					(size 1.27 1.27)
				)
			)
		)
		(duplicate_pad_numbers_are_jumpers no)
		(fp_line
			(start 0.7874 0.4064)
			(end -0.7874 0.4064)
			(stroke
				(width 0.1524)
				(type default)
			)
			(layer "F.SilkS")
		)
		(fp_line
			(start 0.7874 -0.4064)
			(end 0.7874 0.4064)
			(stroke
				(width 0.1524)
				(type default)
			)
			(layer "F.SilkS")
		)
		(fp_line
			(start -0.7874 0.4064)
			(end -0.7874 -0.4064)
			(stroke
				(width 0.1524)
				(type default)
			)
			(layer "F.SilkS")
		)
		(fp_line
			(start -0.7874 -0.4064)
			(end 0.7874 -0.4064)
			(stroke
				(width 0.1524)
				(type default)
			)
			(layer "F.SilkS")
		)
		(fp_line
			(start 0.67945 0.3048)
			(end 0.120396 0.3048)
			(stroke
				(width 0.1)
				(type default)
			)
			(layer "F.Fab")
		)
		(fp_line
			(start 0.67945 -0.3048)
			(end 0.67945 0.3048)
			(stroke
				(width 0.1)
				(type default)
			)
			(layer "F.Fab")
		)
		(fp_line
			(start 0.12065 -0.2794)
			(end 0.12065 -0.3048)
			(stroke
				(width 0.1)
				(type default)
			)
			(layer "F.Fab")
		)
		(fp_line
			(start 0.12065 -0.3048)
			(end 0.67945 -0.3048)
			(stroke
				(width 0.1)
				(type default)
			)
			(layer "F.Fab")
		)
		(fp_line
			(start 0.120396 0.3048)
			(end 0.120396 0.2794)
			(stroke
				(width 0.1)
				(type default)
			)
			(layer "F.Fab")
		)
		(fp_line
			(start 0.120396 0.2794)
			(end -0.12065 0.2794)
			(stroke
				(width 0.1)
				(type default)
			)
			(layer "F.Fab")
		)
		(fp_line
			(start -0.12065 0.3048)
			(end -0.67945 0.3048)
			(stroke
				(width 0.1)
				(type default)
			)
			(layer "F.Fab")
		)
		(fp_line
			(start -0.12065 0.2794)
			(end -0.12065 0.3048)
			(stroke
				(width 0.1)
				(type default)
			)
			(layer "F.Fab")
		)
		(fp_line
			(start -0.12065 -0.2794)
			(end 0.12065 -0.2794)
			(stroke
				(width 0.1)
				(type default)
			)
			(layer "F.Fab")
		)
		(fp_line
			(start -0.12065 -0.305054)
			(end -0.12065 -0.2794)
			(stroke
				(width 0.1)
				(type default)
			)
			(layer "F.Fab")
		)
		(fp_line
			(start -0.67945 0.3048)
			(end -0.67945 -0.305054)
			(stroke
				(width 0.1)
				(type default)
			)
			(layer "F.Fab")
		)
		(fp_line
			(start -0.67945 -0.305054)
			(end -0.12065 -0.305054)
			(stroke
				(width 0.1)
				(type default)
			)
			(layer "F.Fab")
		)
		(pad "1" smd circle
			(at -0.40005 0 180)
			(size 0 0)
			(layers "F.Cu" "F.Mask" "F.Paste")
			(net "P3V3_AUX")
		)
		(pad "2" smd circle
			(at 0.40005 0 180)
			(size 0 0)
			(layers "F.Cu" "F.Mask" "F.Paste")
			(net "USB_DEBUG_RST_BTN_N")
		)
	)
	(footprint ""
		(layer "F.Cu")
		(at 231.844596 -280.583386 180)
		(property "Reference" "R786"
			(at 0 0 180)
			(layer "F.SilkS")
			(hide yes)
			(effects
				(font
					(size 1.27 1.27)
				)
			)
		)
		(property "Value" ""
			(at 0 0 180)
			(layer "F.Fab")
			(effects
				(font
					(size 1.27 1.27)
				)
			)
		)
		(duplicate_pad_numbers_are_jumpers no)
		(fp_line
			(start 0.7874 0.4064)
			(end -0.7874 0.4064)
			(stroke
				(width 0.1524)
				(type default)
			)
			(layer "F.SilkS")
		)
		(fp_line
			(start 0.7874 -0.4064)
			(end 0.7874 0.4064)
			(stroke
				(width 0.1524)
				(type default)
			)
			(layer "F.SilkS")
		)
		(fp_line
			(start -0.7874 0.4064)
			(end -0.7874 -0.4064)
			(stroke
				(width 0.1524)
				(type default)
			)
			(layer "F.SilkS")
		)
		(fp_line
			(start -0.7874 -0.4064)
			(end 0.7874 -0.4064)
			(stroke
				(width 0.1524)
				(type default)
			)
			(layer "F.SilkS")
		)
		(fp_line
			(start 0.67945 0.3048)
			(end 0.120396 0.3048)
			(stroke
				(width 0.1)
				(type default)
			)
			(layer "F.Fab")
		)
		(fp_line
			(start 0.67945 -0.3048)
			(end 0.67945 0.3048)
			(stroke
				(width 0.1)
				(type default)
			)
			(layer "F.Fab")
		)
		(fp_line
			(start 0.12065 -0.2794)
			(end 0.12065 -0.3048)
			(stroke
				(width 0.1)
				(type default)
			)
			(layer "F.Fab")
		)
		(fp_line
			(start 0.12065 -0.3048)
			(end 0.67945 -0.3048)
			(stroke
				(width 0.1)
				(type default)
			)
			(layer "F.Fab")
		)
		(fp_line
			(start 0.120396 0.3048)
			(end 0.120396 0.2794)
			(stroke
				(width 0.1)
				(type default)
			)
			(layer "F.Fab")
		)
		(fp_line
			(start 0.120396 0.2794)
			(end -0.12065 0.2794)
			(stroke
				(width 0.1)
				(type default)
			)
			(layer "F.Fab")
		)
		(fp_line
			(start -0.12065 0.3048)
			(end -0.67945 0.3048)
			(stroke
				(width 0.1)
				(type default)
			)
			(layer "F.Fab")
		)
		(fp_line
			(start -0.12065 0.2794)
			(end -0.12065 0.3048)
			(stroke
				(width 0.1)
				(type default)
			)
			(layer "F.Fab")
		)
		(fp_line
			(start -0.12065 -0.2794)
			(end 0.12065 -0.2794)
			(stroke
				(width 0.1)
				(type default)
			)
			(layer "F.Fab")
		)
		(fp_line
			(start -0.12065 -0.305054)
			(end -0.12065 -0.2794)
			(stroke
				(width 0.1)
				(type default)
			)
			(layer "F.Fab")
		)
		(fp_line
			(start -0.67945 0.3048)
			(end -0.67945 -0.305054)
			(stroke
				(width 0.1)
				(type default)
			)
			(layer "F.Fab")
		)
		(fp_line
			(start -0.67945 -0.305054)
			(end -0.12065 -0.305054)
			(stroke
				(width 0.1)
				(type default)
			)
			(layer "F.Fab")
		)
		(pad "1" smd circle
			(at -0.40005 0 180)
			(size 0 0)
			(layers "F.Cu" "F.Mask" "F.Paste")
			(net "SMB_BIC_I2C6_MUX_PEX_ADC_R_SCL")
		)
		(pad "2" smd circle
			(at 0.40005 0 180)
			(size 0 0)
			(layers "F.Cu" "F.Mask" "F.Paste")
			(net "SMB_PEX1_P1V25_ADC_SCL")
		)
	)
	(footprint ""
		(layer "F.Cu")
		(at 385.79679 -246.059706 180)
		(property "Reference" "C2574"
			(at 0 0 180)
			(layer "F.SilkS")
			(hide yes)
			(effects
				(font
					(size 1.27 1.27)
				)
			)
		)
		(property "Value" ""
			(at 0 0 180)
			(layer "F.Fab")
			(effects
				(font
					(size 1.27 1.27)
				)
			)
		)
		(duplicate_pad_numbers_are_jumpers no)
		(fp_line
			(start 0.7874 0.4064)
			(end -0.7874 0.4064)
			(stroke
				(width 0.1524)
				(type default)
			)
			(layer "F.SilkS")
		)
		(fp_line
			(start 0.7874 -0.4064)
			(end 0.7874 0.4064)
			(stroke
				(width 0.1524)
				(type default)
			)
			(layer "F.SilkS")
		)
		(fp_line
			(start -0.7874 0.4064)
			(end -0.7874 -0.4064)
			(stroke
				(width 0.1524)
				(type default)
			)
			(layer "F.SilkS")
		)
		(fp_line
			(start -0.7874 -0.4064)
			(end 0.7874 -0.4064)
			(stroke
				(width 0.1524)
				(type default)
			)
			(layer "F.SilkS")
		)
		(fp_line
			(start 0.67945 0.3048)
			(end 0.120396 0.3048)
			(stroke
				(width 0.1)
				(type default)
			)
			(layer "F.Fab")
		)
		(fp_line
			(start 0.67945 -0.3048)
			(end 0.67945 0.3048)
			(stroke
				(width 0.1)
				(type default)
			)
			(layer "F.Fab")
		)
		(fp_line
			(start 0.12065 -0.2794)
			(end 0.12065 -0.3048)
			(stroke
				(width 0.1)
				(type default)
			)
			(layer "F.Fab")
		)
		(fp_line
			(start 0.12065 -0.3048)
			(end 0.67945 -0.3048)
			(stroke
				(width 0.1)
				(type default)
			)
			(layer "F.Fab")
		)
		(fp_line
			(start 0.120396 0.3048)
			(end 0.120396 0.2794)
			(stroke
				(width 0.1)
				(type default)
			)
			(layer "F.Fab")
		)
		(fp_line
			(start 0.120396 0.2794)
			(end -0.12065 0.2794)
			(stroke
				(width 0.1)
				(type default)
			)
			(layer "F.Fab")
		)
		(fp_line
			(start -0.12065 0.3048)
			(end -0.67945 0.3048)
			(stroke
				(width 0.1)
				(type default)
			)
			(layer "F.Fab")
		)
		(fp_line
			(start -0.12065 0.2794)
			(end -0.12065 0.3048)
			(stroke
				(width 0.1)
				(type default)
			)
			(layer "F.Fab")
		)
		(fp_line
			(start -0.12065 -0.2794)
			(end 0.12065 -0.2794)
			(stroke
				(width 0.1)
				(type default)
			)
			(layer "F.Fab")
		)
		(fp_line
			(start -0.12065 -0.305054)
			(end -0.12065 -0.2794)
			(stroke
				(width 0.1)
				(type default)
			)
			(layer "F.Fab")
		)
		(fp_line
			(start -0.67945 0.3048)
			(end -0.67945 -0.305054)
			(stroke
				(width 0.1)
				(type default)
			)
			(layer "F.Fab")
		)
		(fp_line
			(start -0.67945 -0.305054)
			(end -0.12065 -0.305054)
			(stroke
				(width 0.1)
				(type default)
			)
			(layer "F.Fab")
		)
		(pad "1" smd circle
			(at -0.40005 0 180)
			(size 0 0)
			(layers "F.Cu" "F.Mask" "F.Paste")
			(net "P1V8_SDB_VCORE")
		)
		(pad "2" smd circle
			(at 0.40005 0 180)
			(size 0 0)
			(layers "F.Cu" "F.Mask" "F.Paste")
			(net "GND")
		)
	)
	(footprint ""
		(layer "F.Cu")
		(at 371.12067 -70.307454 90)
		(property "Reference" "PC888"
			(at 0 0 90)
			(layer "F.SilkS")
			(hide yes)
			(effects
				(font
					(size 1.27 1.27)
				)
			)
		)
		(property "Value" ""
			(at 0 0 90)
			(layer "F.Fab")
			(effects
				(font
					(size 1.27 1.27)
				)
			)
		)
		(duplicate_pad_numbers_are_jumpers no)
		(fp_line
			(start 0.7874 -0.4064)
			(end 0.7874 0.4064)
			(stroke
				(width 0.1524)
				(type default)
			)
			(layer "F.SilkS")
		)
		(fp_line
			(start -0.7874 -0.4064)
			(end 0.7874 -0.4064)
			(stroke
				(width 0.1524)
				(type default)
			)
			(layer "F.SilkS")
		)
		(fp_line
			(start 0.7874 0.4064)
			(end -0.7874 0.4064)
			(stroke
				(width 0.1524)
				(type default)
			)
			(layer "F.SilkS")
		)
		(fp_line
			(start -0.7874 0.4064)
			(end -0.7874 -0.4064)
			(stroke
				(width 0.1524)
				(type default)
			)
			(layer "F.SilkS")
		)
		(fp_line
			(start -0.12065 -0.305054)
			(end -0.12065 -0.2794)
			(stroke
				(width 0.1)
				(type default)
			)
			(layer "F.Fab")
		)
		(fp_line
			(start -0.67945 -0.305054)
			(end -0.12065 -0.305054)
			(stroke
				(width 0.1)
				(type default)
			)
			(layer "F.Fab")
		)
		(fp_line
			(start 0.67945 -0.3048)
			(end 0.67945 0.3048)
			(stroke
				(width 0.1)
				(type default)
			)
			(layer "F.Fab")
		)
		(fp_line
			(start 0.12065 -0.3048)
			(end 0.67945 -0.3048)
			(stroke
				(width 0.1)
				(type default)
			)
			(layer "F.Fab")
		)
		(fp_line
			(start 0.12065 -0.2794)
			(end 0.12065 -0.3048)
			(stroke
				(width 0.1)
				(type default)
			)
			(layer "F.Fab")
		)
		(fp_line
			(start -0.12065 -0.2794)
			(end 0.12065 -0.2794)
			(stroke
				(width 0.1)
				(type default)
			)
			(layer "F.Fab")
		)
		(fp_line
			(start 0.120396 0.2794)
			(end -0.12065 0.2794)
			(stroke
				(width 0.1)
				(type default)
			)
			(layer "F.Fab")
		)
		(fp_line
			(start -0.12065 0.2794)
			(end -0.12065 0.3048)
			(stroke
				(width 0.1)
				(type default)
			)
			(layer "F.Fab")
		)
		(fp_line
			(start 0.67945 0.3048)
			(end 0.120396 0.3048)
			(stroke
				(width 0.1)
				(type default)
			)
			(layer "F.Fab")
		)
		(fp_line
			(start 0.120396 0.3048)
			(end 0.120396 0.2794)
			(stroke
				(width 0.1)
				(type default)
			)
			(layer "F.Fab")
		)
		(fp_line
			(start -0.12065 0.3048)
			(end -0.67945 0.3048)
			(stroke
				(width 0.1)
				(type default)
			)
			(layer "F.Fab")
		)
		(fp_line
			(start -0.67945 0.3048)
			(end -0.67945 -0.305054)
			(stroke
				(width 0.1)
				(type default)
			)
			(layer "F.Fab")
		)
		(pad "1" smd circle
			(at -0.40005 0 90)
			(size 0 0)
			(layers "F.Cu" "F.Mask" "F.Paste")
			(net "P12V_AUX")
		)
		(pad "2" smd circle
			(at 0.40005 0 90)
			(size 0 0)
			(layers "F.Cu" "F.Mask" "F.Paste")
			(net "GND")
		)
	)
	(footprint ""
		(layer "F.Cu")
		(at 155.380436 -107.403138)
		(property "Reference" "C267"
			(at 0 0 0)
			(layer "F.SilkS")
			(hide yes)
			(effects
				(font
					(size 1.27 1.27)
				)
			)
		)
		(property "Value" ""
			(at 0 0 0)
			(layer "F.Fab")
			(effects
				(font
					(size 1.27 1.27)
				)
			)
		)
		(duplicate_pad_numbers_are_jumpers no)
		(fp_line
			(start -0.299974 -0.150114)
			(end 0.299974 -0.150114)
			(stroke
				(width 0.1)
				(type default)
			)
			(layer "F.Fab")
		)
		(fp_line
			(start -0.299974 0.150114)
			(end -0.299974 -0.150114)
			(stroke
				(width 0.1)
				(type default)
			)
			(layer "F.Fab")
		)
		(fp_line
			(start 0.299974 -0.150114)
			(end 0.299974 0.150114)
			(stroke
				(width 0.1)
				(type default)
			)
			(layer "F.Fab")
		)
		(fp_line
			(start 0.299974 0.150114)
			(end -0.299974 0.150114)
			(stroke
				(width 0.1)
				(type default)
			)
			(layer "F.Fab")
		)
		(pad "1" smd rect
			(at -0.2667 0)
			(size 0.3048 0.381)
			(layers "F.Cu" "F.Mask" "F.Paste")
			(net "P5E_PEX1_STN1_TX_DN<20>")
		)
		(pad "2" smd rect
			(at 0.2667 0)
			(size 0.3048 0.381)
			(layers "F.Cu" "F.Mask" "F.Paste")
			(net "P5E_PEX1_STN1_TX_C_DN<20>")
		)
	)
	(footprint ""
		(layer "F.Cu")
		(at 413.293052 -350.098614 90)
		(property "Reference" "C823"
			(at 0 0 90)
			(layer "F.SilkS")
			(hide yes)
			(effects
				(font
					(size 1.27 1.27)
				)
			)
		)
		(property "Value" ""
			(at 0 0 90)
			(layer "F.Fab")
			(effects
				(font
					(size 1.27 1.27)
				)
			)
		)
		(duplicate_pad_numbers_are_jumpers no)
		(fp_line
			(start 0.299974 -0.150114)
			(end 0.299974 0.150114)
			(stroke
				(width 0.1)
				(type default)
			)
			(layer "F.Fab")
		)
		(fp_line
			(start -0.299974 -0.150114)
			(end 0.299974 -0.150114)
			(stroke
				(width 0.1)
				(type default)
			)
			(layer "F.Fab")
		)
		(fp_line
			(start 0.299974 0.150114)
			(end -0.299974 0.150114)
			(stroke
				(width 0.1)
				(type default)
			)
			(layer "F.Fab")
		)
		(fp_line
			(start -0.299974 0.150114)
			(end -0.299974 -0.150114)
			(stroke
				(width 0.1)
				(type default)
			)
			(layer "F.Fab")
		)
		(pad "1" smd rect
			(at -0.2667 0 90)
			(size 0.3048 0.381)
			(layers "F.Cu" "F.Mask" "F.Paste")
			(net "P5E_PEX3_STN7_TX_DN<113>")
		)
		(pad "2" smd rect
			(at 0.2667 0 90)
			(size 0.3048 0.381)
			(layers "F.Cu" "F.Mask" "F.Paste")
			(net "P5E_PEX3_STN7_TX_C_DN<113>")
		)
	)
	(footprint ""
		(layer "F.Cu")
		(at 439.168032 -289.230816 90)
		(property "Reference" "R4004"
			(at 0 0 90)
			(layer "F.SilkS")
			(hide yes)
			(effects
				(font
					(size 1.27 1.27)
				)
			)
		)
		(property "Value" ""
			(at 0 0 90)
			(layer "F.Fab")
			(effects
				(font
					(size 1.27 1.27)
				)
			)
		)
		(duplicate_pad_numbers_are_jumpers no)
		(fp_line
			(start 0.7874 -0.4064)
			(end 0.7874 0.4064)
			(stroke
				(width 0.1524)
				(type default)
			)
			(layer "F.SilkS")
		)
		(fp_line
			(start -0.7874 -0.4064)
			(end 0.7874 -0.4064)
			(stroke
				(width 0.1524)
				(type default)
			)
			(layer "F.SilkS")
		)
		(fp_line
			(start 0.7874 0.4064)
			(end -0.7874 0.4064)
			(stroke
				(width 0.1524)
				(type default)
			)
			(layer "F.SilkS")
		)
		(fp_line
			(start -0.7874 0.4064)
			(end -0.7874 -0.4064)
			(stroke
				(width 0.1524)
				(type default)
			)
			(layer "F.SilkS")
		)
		(fp_line
			(start -0.12065 -0.305054)
			(end -0.12065 -0.2794)
			(stroke
				(width 0.1)
				(type default)
			)
			(layer "F.Fab")
		)
		(fp_line
			(start -0.67945 -0.305054)
			(end -0.12065 -0.305054)
			(stroke
				(width 0.1)
				(type default)
			)
			(layer "F.Fab")
		)
		(fp_line
			(start 0.67945 -0.3048)
			(end 0.67945 0.3048)
			(stroke
				(width 0.1)
				(type default)
			)
			(layer "F.Fab")
		)
		(fp_line
			(start 0.12065 -0.3048)
			(end 0.67945 -0.3048)
			(stroke
				(width 0.1)
				(type default)
			)
			(layer "F.Fab")
		)
		(fp_line
			(start 0.12065 -0.2794)
			(end 0.12065 -0.3048)
			(stroke
				(width 0.1)
				(type default)
			)
			(layer "F.Fab")
		)
		(fp_line
			(start -0.12065 -0.2794)
			(end 0.12065 -0.2794)
			(stroke
				(width 0.1)
				(type default)
			)
			(layer "F.Fab")
		)
		(fp_line
			(start 0.120396 0.2794)
			(end -0.12065 0.2794)
			(stroke
				(width 0.1)
				(type default)
			)
			(layer "F.Fab")
		)
		(fp_line
			(start -0.12065 0.2794)
			(end -0.12065 0.3048)
			(stroke
				(width 0.1)
				(type default)
			)
			(layer "F.Fab")
		)
		(fp_line
			(start 0.67945 0.3048)
			(end 0.120396 0.3048)
			(stroke
				(width 0.1)
				(type default)
			)
			(layer "F.Fab")
		)
		(fp_line
			(start 0.120396 0.3048)
			(end 0.120396 0.2794)
			(stroke
				(width 0.1)
				(type default)
			)
			(layer "F.Fab")
		)
		(fp_line
			(start -0.12065 0.3048)
			(end -0.67945 0.3048)
			(stroke
				(width 0.1)
				(type default)
			)
			(layer "F.Fab")
		)
		(fp_line
			(start -0.67945 0.3048)
			(end -0.67945 -0.305054)
			(stroke
				(width 0.1)
				(type default)
			)
			(layer "F.Fab")
		)
		(pad "1" smd circle
			(at -0.40005 0 90)
			(size 0 0)
			(layers "F.Cu" "F.Mask" "F.Paste")
			(net "SMB_PEX3_FPGA_SCL")
		)
		(pad "2" smd circle
			(at 0.40005 0 90)
			(size 0 0)
			(layers "F.Cu" "F.Mask" "F.Paste")
			(net "SMB_PEX3_HOST_LS_SCL")
		)
	)
)
